(kicad_pcb
	(version 20260206)
	(generator "pcbnew")
	(generator_version "10.0")
	(general
		(thickness 1.6)
		(legacy_teardrops no)
	)
	(paper "A4")
	(title_block
		(title "Bryce Canyon_Front Panel_16369-1_OCP.brd")
		(comment 1 "Bryce Canyon / footprints 15-21 of 154")
	)
	(layers
		(0 "F.Cu" signal "TOP")
		(4 "In1.Cu" signal "L2GND")
		(6 "In2.Cu" signal "L3VCC")
		(2 "B.Cu" signal "BOTTOM")
		(9 "F.Adhes" user "F.Adhesive")
		(11 "B.Adhes" user "B.Adhesive")
		(13 "F.Paste" user "Package Geometry/Pastemask Top")
		(15 "B.Paste" user "Package Geometry/Pastemask Bottom")
		(5 "F.SilkS" user "Ref Des/Silkscreen Top")
		(7 "B.SilkS" user "Ref Des/Silkscreen Bottom")
		(1 "F.Mask" user "Board Geometry/Soldermask Top")
		(3 "B.Mask" user "Board Geometry/Soldermask Bottom")
		(17 "Dwgs.User" user "User.Drawings")
		(19 "Cmts.User" user "User.Comments")
		(21 "Eco1.User" user "User.Eco1")
		(23 "Eco2.User" user "User.Eco2")
		(25 "Edge.Cuts" user "Board Geometry/Outline")
		(27 "Margin" user)
		(31 "F.CrtYd" user "Package Geometry/Place Bound Top")
		(29 "B.CrtYd" user "Package Geometry/Place Bound Bottom")
		(35 "F.Fab" user "Ref Des/Assembly Top")
		(33 "B.Fab" user "Ref Des/Assembly Bottom")
	)
	(footprint ""
		(layer "F.Cu")
		(at 54.706012 -7.01167 180)
		(property "Reference" "R74"
			(at 0 0 180)
			(layer "F.SilkS")
			(hide yes)
			(effects
				(font
					(size 1.27 1.27)
				)
			)
		)
		(property "Value" "4K7R2F-GP"
			(at 0.064008 -3.993896 180)
			(unlocked yes)
			(layer "F.Fab")
			(hide yes)
			(effects
				(font
					(size 1.016 1.016)
					(thickness 0.1524)
				)
			)
		)
		(property "Device Type" "R402H16"
			(at 0.064008 -5.517896 180)
			(unlocked yes)
			(layer "F.Fab")
			(hide yes)
			(effects
				(font
					(size 1.016 1.016)
					(thickness 0.1524)
				)
			)
		)
		(duplicate_pad_numbers_are_jumpers no)
		(fp_line
			(start 0.508 -0.9398)
			(end -0.508 -0.9398)
			(stroke
				(width 0.1524)
				(type default)
			)
			(layer "F.SilkS")
		)
		(fp_line
			(start -0.508 -0.9398)
			(end -0.508 0.9398)
			(stroke
				(width 0.1524)
				(type default)
			)
			(layer "F.SilkS")
		)
		(fp_rect
			(start -0.508 0.9398)
			(end 0.508 -0.9398)
			(stroke
				(width 0)
				(type default)
			)
			(fill no)
			(layer "F.CrtYd")
		)
		(fp_rect
			(start -0.508 0.9398)
			(end 0.508 -0.9398)
			(stroke
				(width 0)
				(type default)
			)
			(fill no)
			(layer "F.Fab")
		)
		(pad "1" smd custom
			(at 0 -0.4445 180)
			(size 0.1397 0.1397)
			(layers "F.Cu" "F.Mask" "F.Paste")
			(net "P3V3_STBY_B")
			(options
				(clearance outline)
				(anchor circle)
			)
			(primitives
				(gr_poly
					(pts
						(arc
							(start -0.1778 -0.2794)
							(mid -0.249642 -0.249642)
							(end -0.2794 -0.1778)
						)
						(arc
							(start -0.2794 0.1778)
							(mid -0.249642 0.249642)
							(end -0.1778 0.2794)
						)
						(arc
							(start 0.1778 0.2794)
							(mid 0.249642 0.249642)
							(end 0.2794 0.1778)
						)
						(arc
							(start 0.2794 -0.1778)
							(mid 0.249642 -0.249642)
							(end 0.1778 -0.2794)
						)
					)
					(width 0)
					(fill yes)
				)
			)
		)
		(pad "2" smd custom
			(at 0 0.4445 180)
			(size 0.1397 0.1397)
			(layers "F.Cu" "F.Mask" "F.Paste")
			(net "TCA9555_B_A2")
			(options
				(clearance outline)
				(anchor circle)
			)
			(primitives
				(gr_poly
					(pts
						(arc
							(start -0.1778 -0.2794)
							(mid -0.249642 -0.249642)
							(end -0.2794 -0.1778)
						)
						(arc
							(start -0.2794 0.1778)
							(mid -0.249642 0.249642)
							(end -0.1778 0.2794)
						)
						(arc
							(start 0.1778 0.2794)
							(mid 0.249642 0.249642)
							(end 0.2794 0.1778)
						)
						(arc
							(start 0.2794 -0.1778)
							(mid 0.249642 -0.249642)
							(end 0.1778 -0.2794)
						)
					)
					(width 0)
					(fill yes)
				)
			)
		)
	)
	(footprint ""
		(layer "F.Cu")
		(at 50.673 -48.7934 -90)
		(property "Reference" "U8"
			(at 0 0 270)
			(layer "F.SilkS")
			(hide yes)
			(effects
				(font
					(size 1.27 1.27)
				)
			)
		)
		(property "Value" "TMP75AIDGKR-GP"
			(at -0.1143 -9.1948 270)
			(unlocked yes)
			(layer "F.Fab")
			(hide yes)
			(effects
				(font
					(size 1.016 1.016)
					(thickness 0.1524)
				)
			)
		)
		(property "Device Type" "MSOP8-1H44"
			(at -0.1143 -10.795 270)
			(unlocked yes)
			(layer "F.Fab")
			(hide yes)
			(effects
				(font
					(size 1.016 1.016)
					(thickness 0.1524)
				)
			)
		)
		(duplicate_pad_numbers_are_jumpers no)
		(fp_line
			(start -1.778 1.0922)
			(end -1.778 3.048)
			(stroke
				(width 0.508)
				(type default)
			)
			(layer "F.SilkS")
		)
		(fp_line
			(start -1.9558 1.016)
			(end 1.0795 1.016)
			(stroke
				(width 0.1524)
				(type default)
			)
			(layer "F.SilkS")
		)
		(fp_line
			(start 1.0795 1.016)
			(end 1.0795 -1.016)
			(stroke
				(width 0.1524)
				(type default)
			)
			(layer "F.SilkS")
		)
		(fp_line
			(start -1.4478 -0.0381)
			(end -1.9558 0.4699)
			(stroke
				(width 0.1524)
				(type default)
			)
			(layer "F.SilkS")
		)
		(fp_line
			(start -1.9558 -0.5461)
			(end -1.4478 -0.0381)
			(stroke
				(width 0.1524)
				(type default)
			)
			(layer "F.SilkS")
		)
		(fp_line
			(start -1.9558 -1.016)
			(end -1.9558 1.016)
			(stroke
				(width 0.1524)
				(type default)
			)
			(layer "F.SilkS")
		)
		(fp_line
			(start 1.0795 -1.016)
			(end -1.9558 -1.016)
			(stroke
				(width 0.1524)
				(type default)
			)
			(layer "F.SilkS")
		)
		(fp_poly
			(pts
				(xy -1.1557 -1.016) (xy -1.1557 1.016) (xy 1.1557 1.016) (xy 1.1557 -1.016)
			)
			(stroke
				(width 0)
				(type default)
			)
			(fill yes)
			(layer "F.SilkS")
		)
		(fp_rect
			(start -1.4986 2.4511)
			(end 1.4986 -2.4511)
			(stroke
				(width 0)
				(type default)
			)
			(fill no)
			(layer "F.CrtYd")
		)
		(fp_poly
			(pts
				(xy -2.032 3.302) (xy -2.032 -3.302) (xy 2.032 -3.302) (xy 2.032 -2.1209) (xy 1.4986 -2.1209) (xy 1.4986 -2.4511)
				(xy -1.4986 -2.4511) (xy -1.4986 2.4511) (xy 1.4986 2.4511) (xy 1.4986 -2.1082) (xy 2.032 -2.1082)
				(xy 2.032 3.302)
			)
			(stroke
				(width 0)
				(type default)
			)
			(fill no)
			(layer "F.CrtYd")
		)
		(fp_rect
			(start -2.032 3.302)
			(end 2.032 -3.302)
			(stroke
				(width 0)
				(type default)
			)
			(fill no)
			(layer "F.Fab")
		)
		(pad "1" smd rect
			(at -0.97536 2.05486 270)
			(size 0.3556 1.524)
			(layers "F.Cu" "F.Mask" "F.Paste")
			(net "TEMP_2_SDA")
		)
		(pad "2" smd rect
			(at -0.32512 2.05486 270)
			(size 0.3556 1.524)
			(layers "F.Cu" "F.Mask" "F.Paste")
			(net "TEMP_2_SCL")
		)
		(pad "3" smd rect
			(at 0.32512 2.05486 270)
			(size 0.3556 1.524)
			(layers "F.Cu" "F.Mask" "F.Paste")
			(net "TEMP_2_ALERT")
		)
		(pad "4" smd rect
			(at 0.97536 2.05486 270)
			(size 0.3556 1.524)
			(layers "F.Cu" "F.Mask" "F.Paste")
			(net "GND")
		)
		(pad "5" smd rect
			(at 0.97536 -2.05486 270)
			(size 0.3556 1.524)
			(layers "F.Cu" "F.Mask" "F.Paste")
			(net "TEMP_2_A2")
		)
		(pad "6" smd rect
			(at 0.32512 -2.05486 270)
			(size 0.3556 1.524)
			(layers "F.Cu" "F.Mask" "F.Paste")
			(net "TEMP_2_A1")
		)
		(pad "7" smd rect
			(at -0.32512 -2.05486 270)
			(size 0.3556 1.524)
			(layers "F.Cu" "F.Mask" "F.Paste")
			(net "TEMP_2_A0")
		)
		(pad "8" smd rect
			(at -0.97536 -2.05486 270)
			(size 0.3556 1.524)
			(layers "F.Cu" "F.Mask" "F.Paste")
			(net "P3V3_STBY_B")
		)
	)
	(footprint ""
		(layer "F.Cu")
		(at 55.0164 -29.2608 90)
		(property "Reference" "C18"
			(at 0 0 90)
			(layer "F.SilkS")
			(hide yes)
			(effects
				(font
					(size 1.27 1.27)
				)
			)
		)
		(property "Value" "SCD1U16V2KX-3GP"
			(at 1.1811 -3.3909 90)
			(unlocked yes)
			(layer "F.Fab")
			(hide yes)
			(effects
				(font
					(size 2.54 2.54)
					(thickness 0.381)
				)
			)
		)
		(property "Device Type" "C402H22"
			(at 1.1811 -4.9149 90)
			(unlocked yes)
			(layer "F.Fab")
			(hide yes)
			(effects
				(font
					(size 2.54 2.54)
					(thickness 0.381)
				)
			)
		)
		(duplicate_pad_numbers_are_jumpers no)
		(fp_rect
			(start -0.4318 0.9525)
			(end 0.4318 -0.9525)
			(stroke
				(width 0)
				(type default)
			)
			(fill no)
			(layer "F.CrtYd")
		)
		(fp_rect
			(start -0.4318 0.9525)
			(end 0.4318 -0.9525)
			(stroke
				(width 0)
				(type default)
			)
			(fill no)
			(layer "F.Fab")
		)
		(pad "1" smd custom
			(at 0 -0.4445 90)
			(size 0.1524 0.1524)
			(layers "F.Cu" "F.Mask" "F.Paste")
			(net "P3V3_STBY_B")
			(options
				(clearance outline)
				(anchor circle)
			)
			(primitives
				(gr_poly
					(pts
						(arc
							(start 0.3048 -0.2032)
							(mid 0.275042 -0.275042)
							(end 0.2032 -0.3048)
						)
						(arc
							(start -0.2032 -0.3048)
							(mid -0.275042 -0.275042)
							(end -0.3048 -0.2032)
						)
						(arc
							(start -0.3048 0.2032)
							(mid -0.275042 0.275042)
							(end -0.2032 0.3048)
						)
						(arc
							(start 0.2032 0.3048)
							(mid 0.275042 0.275042)
							(end 0.3048 0.2032)
						)
					)
					(width 0)
					(fill yes)
				)
			)
		)
		(pad "2" smd custom
			(at 0 0.4445 90)
			(size 0.1524 0.1524)
			(layers "F.Cu" "F.Mask" "F.Paste")
			(net "GND")
			(options
				(clearance outline)
				(anchor circle)
			)
			(primitives
				(gr_poly
					(pts
						(arc
							(start 0.3048 -0.2032)
							(mid 0.275042 -0.275042)
							(end 0.2032 -0.3048)
						)
						(arc
							(start -0.2032 -0.3048)
							(mid -0.275042 -0.275042)
							(end -0.3048 -0.2032)
						)
						(arc
							(start -0.3048 0.2032)
							(mid -0.275042 0.275042)
							(end -0.2032 0.3048)
						)
						(arc
							(start 0.2032 0.3048)
							(mid 0.275042 0.275042)
							(end 0.3048 0.2032)
						)
					)
					(width 0)
					(fill yes)
				)
			)
		)
	)
	(footprint ""
		(layer "F.Cu")
		(at 9.525 -23.2156 90)
		(property "Reference" "R77"
			(at 0 0 90)
			(layer "F.SilkS")
			(hide yes)
			(effects
				(font
					(size 1.27 1.27)
				)
			)
		)
		(property "Value" "4K7R2F-GP"
			(at 0.064008 -3.993896 90)
			(unlocked yes)
			(layer "F.Fab")
			(hide yes)
			(effects
				(font
					(size 1.016 1.016)
					(thickness 0.1524)
				)
			)
		)
		(property "Device Type" "R402H16"
			(at 0.064008 -5.517896 90)
			(unlocked yes)
			(layer "F.Fab")
			(hide yes)
			(effects
				(font
					(size 1.016 1.016)
					(thickness 0.1524)
				)
			)
		)
		(duplicate_pad_numbers_are_jumpers no)
		(fp_line
			(start 0.508 -0.9398)
			(end -0.508 -0.9398)
			(stroke
				(width 0.1524)
				(type default)
			)
			(layer "F.SilkS")
		)
		(fp_line
			(start -0.508 -0.9398)
			(end -0.508 0.9398)
			(stroke
				(width 0.1524)
				(type default)
			)
			(layer "F.SilkS")
		)
		(fp_rect
			(start -0.508 0.9398)
			(end 0.508 -0.9398)
			(stroke
				(width 0)
				(type default)
			)
			(fill no)
			(layer "F.CrtYd")
		)
		(fp_rect
			(start -0.508 0.9398)
			(end 0.508 -0.9398)
			(stroke
				(width 0)
				(type default)
			)
			(fill no)
			(layer "F.Fab")
		)
		(pad "1" smd custom
			(at 0 -0.4445 90)
			(size 0.1397 0.1397)
			(layers "F.Cu" "F.Mask" "F.Paste")
			(net "P3V3_STBY_A")
			(options
				(clearance outline)
				(anchor circle)
			)
			(primitives
				(gr_poly
					(pts
						(arc
							(start -0.1778 -0.2794)
							(mid -0.249642 -0.249642)
							(end -0.2794 -0.1778)
						)
						(arc
							(start -0.2794 0.1778)
							(mid -0.249642 0.249642)
							(end -0.1778 0.2794)
						)
						(arc
							(start 0.1778 0.2794)
							(mid 0.249642 0.249642)
							(end 0.2794 0.1778)
						)
						(arc
							(start 0.2794 -0.1778)
							(mid 0.249642 -0.249642)
							(end 0.1778 -0.2794)
						)
					)
					(width 0)
					(fill yes)
				)
			)
		)
		(pad "2" smd custom
			(at 0 0.4445 90)
			(size 0.1397 0.1397)
			(layers "F.Cu" "F.Mask" "F.Paste")
			(net "DEBUG_RST_A_BTN_N")
			(options
				(clearance outline)
				(anchor circle)
			)
			(primitives
				(gr_poly
					(pts
						(arc
							(start -0.1778 -0.2794)
							(mid -0.249642 -0.249642)
							(end -0.2794 -0.1778)
						)
						(arc
							(start -0.2794 0.1778)
							(mid -0.249642 0.249642)
							(end -0.1778 0.2794)
						)
						(arc
							(start 0.1778 0.2794)
							(mid 0.249642 0.249642)
							(end 0.2794 0.1778)
						)
						(arc
							(start 0.2794 -0.1778)
							(mid 0.249642 -0.249642)
							(end 0.1778 -0.2794)
						)
					)
					(width 0)
					(fill yes)
				)
			)
		)
	)
	(footprint ""
		(layer "F.Cu")
		(at 2.436622 -62.373764 -90)
		(property "Reference" "C4"
			(at 0 0 270)
			(layer "F.SilkS")
			(hide yes)
			(effects
				(font
					(size 1.27 1.27)
				)
			)
		)
		(property "Value" "SC1U16V3KX-5GP"
			(at 0 -3.5052 270)
			(unlocked yes)
			(layer "F.Fab")
			(hide yes)
			(effects
				(font
					(size 2.54 2.54)
					(thickness 0.381)
				)
			)
		)
		(property "Device Type" "C603H36"
			(at 0 -5.0292 270)
			(unlocked yes)
			(layer "F.Fab")
			(hide yes)
			(effects
				(font
					(size 2.54 2.54)
					(thickness 0.381)
				)
			)
		)
		(duplicate_pad_numbers_are_jumpers no)
		(fp_line
			(start 0.508 0)
			(end -0.508 0)
			(stroke
				(width 0.2032)
				(type default)
			)
			(layer "F.SilkS")
		)
		(fp_rect
			(start -0.5842 1.3335)
			(end 0.5842 -1.3335)
			(stroke
				(width 0)
				(type default)
			)
			(fill no)
			(layer "F.CrtYd")
		)
		(fp_rect
			(start -0.5842 1.3335)
			(end 0.5842 -1.3335)
			(stroke
				(width 0)
				(type default)
			)
			(fill no)
			(layer "F.Fab")
		)
		(pad "1" smd custom
			(at 0 -0.762 270)
			(size 0.2159 0.2159)
			(layers "F.Cu" "F.Mask" "F.Paste")
			(net "P5V_USB_A")
			(options
				(clearance outline)
				(anchor circle)
			)
			(primitives
				(gr_poly
					(pts
						(arc
							(start -0.3302 -0.4318)
							(mid -0.402042 -0.402042)
							(end -0.4318 -0.3302)
						)
						(arc
							(start -0.4318 0.3302)
							(mid -0.402042 0.402042)
							(end -0.3302 0.4318)
						)
						(arc
							(start 0.3302 0.4318)
							(mid 0.402042 0.402042)
							(end 0.4318 0.3302)
						)
						(arc
							(start 0.4318 -0.3302)
							(mid 0.402042 -0.402042)
							(end 0.3302 -0.4318)
						)
					)
					(width 0)
					(fill yes)
				)
			)
		)
		(pad "2" smd custom
			(at 0 0.762 270)
			(size 0.2159 0.2159)
			(layers "F.Cu" "F.Mask" "F.Paste")
			(net "GND")
			(options
				(clearance outline)
				(anchor circle)
			)
			(primitives
				(gr_poly
					(pts
						(arc
							(start -0.3302 -0.4318)
							(mid -0.402042 -0.402042)
							(end -0.4318 -0.3302)
						)
						(arc
							(start -0.4318 0.3302)
							(mid -0.402042 0.402042)
							(end -0.3302 0.4318)
						)
						(arc
							(start 0.3302 0.4318)
							(mid 0.402042 0.402042)
							(end 0.4318 0.3302)
						)
						(arc
							(start 0.4318 -0.3302)
							(mid 0.402042 -0.402042)
							(end 0.3302 -0.4318)
						)
					)
					(width 0)
					(fill yes)
				)
			)
		)
	)
	(footprint ""
		(layer "F.Cu")
		(at 52.197 -44.2976)
		(property "Reference" "R38"
			(at 0 0 0)
			(layer "F.SilkS")
			(hide yes)
			(effects
				(font
					(size 1.27 1.27)
				)
			)
		)
		(property "Value" "0R2J-2-GP"
			(at 0.064008 -4.679696 0)
			(unlocked yes)
			(layer "F.Fab")
			(hide yes)
			(effects
				(font
					(size 2.54 2.54)
					(thickness 0.381)
				)
			)
		)
		(property "Device Type" "R402H16"
			(at 0.064008 -6.203696 0)
			(unlocked yes)
			(layer "F.Fab")
			(hide yes)
			(effects
				(font
					(size 2.54 2.54)
					(thickness 0.381)
				)
			)
		)
		(duplicate_pad_numbers_are_jumpers no)
		(fp_line
			(start -0.508 -0.9398)
			(end -0.508 0.9398)
			(stroke
				(width 0.1524)
				(type default)
			)
			(layer "F.SilkS")
		)
		(fp_line
			(start 0.508 -0.9398)
			(end -0.508 -0.9398)
			(stroke
				(width 0.1524)
				(type default)
			)
			(layer "F.SilkS")
		)
		(fp_rect
			(start -0.508 0.9398)
			(end 0.508 -0.9398)
			(stroke
				(width 0)
				(type default)
			)
			(fill no)
			(layer "F.CrtYd")
		)
		(fp_rect
			(start -0.508 0.9398)
			(end 0.508 -0.9398)
			(stroke
				(width 0)
				(type default)
			)
			(fill no)
			(layer "F.Fab")
		)
		(pad "1" smd custom
			(at 0 -0.4445)
			(size 0.1397 0.1397)
			(layers "F.Cu" "F.Mask" "F.Paste")
			(net "TEMP_2_SCL")
			(options
				(clearance outline)
				(anchor circle)
			)
			(primitives
				(gr_poly
					(pts
						(arc
							(start -0.1778 -0.2794)
							(mid -0.249642 -0.249642)
							(end -0.2794 -0.1778)
						)
						(arc
							(start -0.2794 0.1778)
							(mid -0.249642 0.249642)
							(end -0.1778 0.2794)
						)
						(arc
							(start 0.1778 0.2794)
							(mid 0.249642 0.249642)
							(end 0.2794 0.1778)
						)
						(arc
							(start 0.2794 -0.1778)
							(mid 0.249642 -0.249642)
							(end 0.1778 -0.2794)
						)
					)
					(width 0)
					(fill yes)
				)
			)
		)
		(pad "2" smd custom
			(at 0 0.4445)
			(size 0.1397 0.1397)
			(layers "F.Cu" "F.Mask" "F.Paste")
			(net "I2C_DPB_B_SCL")
			(options
				(clearance outline)
				(anchor circle)
			)
			(primitives
				(gr_poly
					(pts
						(arc
							(start -0.1778 -0.2794)
							(mid -0.249642 -0.249642)
							(end -0.2794 -0.1778)
						)
						(arc
							(start -0.2794 0.1778)
							(mid -0.249642 0.249642)
							(end -0.1778 0.2794)
						)
						(arc
							(start 0.1778 0.2794)
							(mid 0.249642 0.249642)
							(end 0.2794 0.1778)
						)
						(arc
							(start 0.2794 -0.1778)
							(mid 0.249642 -0.249642)
							(end 0.1778 -0.2794)
						)
					)
					(width 0)
					(fill yes)
				)
			)
		)
	)
	(footprint ""
		(layer "F.Cu")
		(at 9.298686 -40.573452 -90)
		(property "Reference" "R25"
			(at 0 0 270)
			(layer "F.SilkS")
			(hide yes)
			(effects
				(font
					(size 1.27 1.27)
				)
			)
		)
		(property "Value" "120R3J-2-GP"
			(at -0.0254 -3.2004 270)
			(unlocked yes)
			(layer "F.Fab")
			(hide yes)
			(effects
				(font
					(size 2.54 2.54)
					(thickness 0.381)
				)
			)
		)
		(property "Device Type" "R603H22"
			(at -0.0254 -4.7244 270)
			(unlocked yes)
			(layer "F.Fab")
			(hide yes)
			(effects
				(font
					(size 2.54 2.54)
					(thickness 0.381)
				)
			)
		)
		(duplicate_pad_numbers_are_jumpers no)
		(fp_line
			(start -0.4826 0)
			(end -0.2032 0)
			(stroke
				(width 0.2032)
				(type default)
			)
			(layer "F.SilkS")
		)
		(fp_line
			(start 0.2032 0)
			(end 0.4826 0)
			(stroke
				(width 0.2032)
				(type default)
			)
			(layer "F.SilkS")
		)
		(fp_rect
			(start -0.5842 1.3335)
			(end 0.5842 -1.3335)
			(stroke
				(width 0)
				(type default)
			)
			(fill no)
			(layer "F.CrtYd")
		)
		(fp_rect
			(start -0.5842 1.3335)
			(end 0.5842 -1.3335)
			(stroke
				(width 0)
				(type default)
			)
			(fill no)
			(layer "F.Fab")
		)
		(pad "1" smd custom
			(at 0 -0.762 270)
			(size 0.2159 0.2159)
			(layers "F.Cu" "F.Mask" "F.Paste")
			(net "P5V_USB_A")
			(options
				(clearance outline)
				(anchor circle)
			)
			(primitives
				(gr_poly
					(pts
						(arc
							(start -0.3302 -0.4318)
							(mid -0.402042 -0.402042)
							(end -0.4318 -0.3302)
						)
						(arc
							(start -0.4318 0.3302)
							(mid -0.402042 0.402042)
							(end -0.3302 0.4318)
						)
						(arc
							(start 0.3302 0.4318)
							(mid 0.402042 0.402042)
							(end 0.4318 0.3302)
						)
						(arc
							(start 0.4318 -0.3302)
							(mid 0.402042 -0.402042)
							(end 0.3302 -0.4318)
						)
					)
					(width 0)
					(fill yes)
				)
			)
		)
		(pad "2" smd custom
			(at 0 0.762 270)
			(size 0.2159 0.2159)
			(layers "F.Cu" "F.Mask" "F.Paste")
			(net "SYS_FAULT_A_R")
			(options
				(clearance outline)
				(anchor circle)
			)
			(primitives
				(gr_poly
					(pts
						(arc
							(start -0.3302 -0.4318)
							(mid -0.402042 -0.402042)
							(end -0.4318 -0.3302)
						)
						(arc
							(start -0.4318 0.3302)
							(mid -0.402042 0.402042)
							(end -0.3302 0.4318)
						)
						(arc
							(start 0.3302 0.4318)
							(mid 0.402042 0.402042)
							(end 0.4318 0.3302)
						)
						(arc
							(start 0.4318 -0.3302)
							(mid 0.402042 -0.402042)
							(end 0.3302 -0.4318)
						)
					)
					(width 0)
					(fill yes)
				)
			)
		)
	)
)
